# TIMECARD (Time Appliance Project (Time Card)) — schematic netlist excerpt (pin names and nets, part order shuffled) for the footprints in the layout excerpt that follows; sources: Cadence DE-HDL packaged netlist, KiCad conversion of R4006-B0001-02_R01.brd

R109  RESISTOR  33OHM 1%  pkg SMC_0402R_H016  page 22 : \1\ = UART_GPS_TX_FPGA_RX ; \2\ = GPS_UART_TXD
R482  RESISTOR  4.7KOHM 1%  pkg SMC_0402R_H016  page 24 : \1\ = XP3R3V_FPGA ; \2\ = MUX3_SEL

(kicad_pcb
	(version 20260206)
	(generator "pcbnew")
	(generator_version "10.0")
	(general
		(thickness 1.6)
		(legacy_teardrops no)
	)
	(paper "A4")
	(title_block
		(title "timecard-production-celestica-r4006 — R4006-B0001-02_R01.brd")
		(comment 1 "Time Appliance Project (Time Card) / footprints 1102-1103 of 1113")
	)
	(layers
		(0 "F.Cu" signal "TOP")
		(4 "In1.Cu" signal "L02_GND1")
		(6 "In2.Cu" signal "L03_SIG1")
		(8 "In3.Cu" signal "L04_GND2")
		(10 "In4.Cu" signal "L05_VCC1")
		(12 "In5.Cu" signal "L06_VCC2")
		(14 "In6.Cu" signal "L07_GND3")
		(16 "In7.Cu" signal "L08_SIG2")
		(18 "In8.Cu" signal "L09_GND4")
		(2 "B.Cu" signal "BOTTOM")
		(9 "F.Adhes" user "F.Adhesive")
		(11 "B.Adhes" user "B.Adhesive")
		(13 "F.Paste" user "Package Geometry/Pastemask Top")
		(15 "B.Paste" user "Package Geometry/Pastemask Bottom")
		(5 "F.SilkS" user "Ref Des/Silkscreen Top")
		(7 "B.SilkS" user "Ref Des/Silkscreen Bottom")
		(1 "F.Mask" user "Board Geometry/Soldermask Top")
		(3 "B.Mask" user "Board Geometry/Soldermask Bottom")
		(17 "Dwgs.User" user "User.Drawings")
		(19 "Cmts.User" user "User.Comments")
		(21 "Eco1.User" user "User.Eco1")
		(23 "Eco2.User" user "User.Eco2")
		(25 "Edge.Cuts" user "Board Geometry/Outline")
		(27 "Margin" user)
		(31 "F.CrtYd" user "Package Geometry/Place Bound Top")
		(29 "B.CrtYd" user "Package Geometry/Place Bound Bottom")
		(35 "F.Fab" user "Ref Des/Assembly Top")
		(33 "B.Fab" user "Ref Des/Assembly Bottom")
	)
	(footprint ""
		(layer "B.Cu")
		(at 126.619 -89.535 -90)
		(property "Reference" "R109"
			(at -2.794 0.03937 270)
			(unlocked yes)
			(layer "B.SilkS")
			(effects
				(font
					(size 0.7874 0.5842)
					(thickness 0.1524)
				)
				(justify mirror)
			)
		)
		(property "Value" "VAL*"
			(at -0.02032 2.13233 270)
			(unlocked yes)
			(layer "B.Fab")
			(hide yes)
			(effects
				(font
					(size 0.7874 0.5842)
					(thickness 0.1524)
				)
				(justify mirror)
			)
		)
		(property "Tolerance" "TOL*"
			(at -0.044704 3.05435 270)
			(unlocked yes)
			(layer "Cmts.User")
			(hide yes)
			(effects
				(font
					(size 0.7874 0.5842)
					(thickness 0.1524)
				)
				(justify mirror)
			)
		)
		(property "User Part Number" "PARTNUM*"
			(at -0.02032 4.024884 270)
			(unlocked yes)
			(layer "Cmts.User")
			(hide yes)
			(effects
				(font
					(size 0.7874 0.5842)
					(thickness 0.1524)
				)
				(justify mirror)
			)
		)
		(property "Device Type" "RESISTOR-G155-133R0-01,33OHM,1%"
			(at -0.008382 1.210564 270)
			(unlocked yes)
			(layer "B.Fab")
			(hide yes)
			(effects
				(font
					(size 0.7874 0.5842)
					(thickness 0.1524)
				)
				(justify mirror)
			)
		)
		(duplicate_pad_numbers_are_jumpers no)
		(fp_line
			(start -1.143 0.5588)
			(end -1.143 -0.5588)
			(stroke
				(width 0.1)
				(type default)
			)
			(layer "B.SilkS")
		)
		(fp_line
			(start 1.143 0.5588)
			(end -1.143 0.5588)
			(stroke
				(width 0.1)
				(type default)
			)
			(layer "B.SilkS")
		)
		(fp_line
			(start -1.143 -0.5588)
			(end 1.143 -0.5588)
			(stroke
				(width 0.1)
				(type default)
			)
			(layer "B.SilkS")
		)
		(fp_line
			(start 1.143 -0.5588)
			(end 1.143 0.5588)
			(stroke
				(width 0.1)
				(type default)
			)
			(layer "B.SilkS")
		)
		(fp_rect
			(start 1.143 0.5588)
			(end -1.143 -0.5588)
			(stroke
				(width 0)
				(type default)
			)
			(fill no)
			(layer "B.CrtYd")
		)
		(fp_line
			(start -0.508 0.3048)
			(end -0.508 -0.3048)
			(stroke
				(width 0.1)
				(type default)
			)
			(layer "B.Fab")
		)
		(fp_line
			(start 0.508 0.3048)
			(end -0.508 0.3048)
			(stroke
				(width 0.1)
				(type default)
			)
			(layer "B.Fab")
		)
		(fp_line
			(start -0.508 -0.3048)
			(end 0.508 -0.3048)
			(stroke
				(width 0.1)
				(type default)
			)
			(layer "B.Fab")
		)
		(fp_line
			(start 0.508 -0.3048)
			(end 0.508 0.3048)
			(stroke
				(width 0.1)
				(type default)
			)
			(layer "B.Fab")
		)
		(pad "1" smd rect
			(at 0.5334 0 90)
			(size 0.7112 0.6096)
			(layers "B.Cu" "B.Mask" "B.Paste")
			(net "UART_GPS_TX_FPGA_RX")
		)
		(pad "2" smd rect
			(at -0.5334 0 90)
			(size 0.7112 0.6096)
			(layers "B.Cu" "B.Mask" "B.Paste")
			(net "GPS_UART_TXD")
		)
		(zone
			(layer "B.Cu")
			(hatch none 0.5)
			(connect_pads
				(clearance 0)
			)
			(min_thickness 0.25)
			(keepout
				(tracks allowed)
				(vias not_allowed)
				(pads allowed)
				(copperpour not_allowed)
				(footprints allowed)
			)
			(placement
				(enabled no)
				(sheetname "")
			)
			(fill
				(thermal_gap 0.5)
				(thermal_bridge_width 0.5)
				(island_removal_mode 0)
			)
			(polygon
				(pts
					(xy 126.3142 -89.4588) (xy 126.9238 -89.4588) (xy 126.9238 -89.6112) (xy 126.3142 -89.6112)
				)
			)
		)
	)
	(footprint ""
		(layer "B.Cu")
		(at 119.761 -24.511 180)
		(property "Reference" "R482"
			(at 0 1.23063 0)
			(unlocked yes)
			(layer "B.SilkS")
			(effects
				(font
					(size 0.7874 0.5842)
					(thickness 0.1524)
				)
				(justify mirror)
			)
		)
		(property "Value" "VAL*"
			(at -0.02032 2.13233 180)
			(unlocked yes)
			(layer "B.Fab")
			(hide yes)
			(effects
				(font
					(size 0.7874 0.5842)
					(thickness 0.1524)
				)
				(justify mirror)
			)
		)
		(property "Tolerance" "TOL*"
			(at -0.044704 3.05435 180)
			(unlocked yes)
			(layer "Cmts.User")
			(hide yes)
			(effects
				(font
					(size 0.7874 0.5842)
					(thickness 0.1524)
				)
				(justify mirror)
			)
		)
		(property "User Part Number" "PARTNUM*"
			(at -0.02032 4.024884 180)
			(unlocked yes)
			(layer "Cmts.User")
			(hide yes)
			(effects
				(font
					(size 0.7874 0.5842)
					(thickness 0.1524)
				)
				(justify mirror)
			)
		)
		(property "Device Type" "RESISTOR-G155-14701-01,4.7KOHMA"
			(at -0.008382 1.210564 180)
			(unlocked yes)
			(layer "B.Fab")
			(hide yes)
			(effects
				(font
					(size 0.7874 0.5842)
					(thickness 0.1524)
				)
				(justify mirror)
			)
		)
		(duplicate_pad_numbers_are_jumpers no)
		(fp_line
			(start 1.143 0.5588)
			(end -1.143 0.5588)
			(stroke
				(width 0.1)
				(type default)
			)
			(layer "B.SilkS")
		)
		(fp_line
			(start 1.143 -0.5588)
			(end 1.143 0.5588)
			(stroke
				(width 0.1)
				(type default)
			)
			(layer "B.SilkS")
		)
		(fp_line
			(start -1.143 0.5588)
			(end -1.143 -0.5588)
			(stroke
				(width 0.1)
				(type default)
			)
			(layer "B.SilkS")
		)
		(fp_line
			(start -1.143 -0.5588)
			(end 1.143 -0.5588)
			(stroke
				(width 0.1)
				(type default)
			)
			(layer "B.SilkS")
		)
		(fp_poly
			(pts
				(xy 1.143 0.5588) (xy -1.143 0.5588) (xy -1.143 -0.5588) (xy 1.143 -0.5588)
			)
			(stroke
				(width 0)
				(type default)
			)
			(fill no)
			(layer "B.CrtYd")
		)
		(fp_line
			(start 0.508 0.3048)
			(end -0.508 0.3048)
			(stroke
				(width 0.1)
				(type default)
			)
			(layer "B.Fab")
		)
		(fp_line
			(start 0.508 -0.3048)
			(end 0.508 0.3048)
			(stroke
				(width 0.1)
				(type default)
			)
			(layer "B.Fab")
		)
		(fp_line
			(start -0.508 0.3048)
			(end -0.508 -0.3048)
			(stroke
				(width 0.1)
				(type default)
			)
			(layer "B.Fab")
		)
		(fp_line
			(start -0.508 -0.3048)
			(end 0.508 -0.3048)
			(stroke
				(width 0.1)
				(type default)
			)
			(layer "B.Fab")
		)
		(pad "1" smd rect
			(at 0.5334 0)
			(size 0.7112 0.6096)
			(layers "B.Cu" "B.Mask" "B.Paste")
			(net "XP3R3V_FPGA")
		)
		(pad "2" smd rect
			(at -0.5334 0)
			(size 0.7112 0.6096)
			(layers "B.Cu" "B.Mask" "B.Paste")
			(net "MUX3_SEL")
		)
		(zone
			(layer "B.Cu")
			(hatch none 0.5)
			(connect_pads
				(clearance 0)
			)
			(min_thickness 0.25)
			(keepout
				(tracks allowed)
				(vias not_allowed)
				(pads allowed)
				(copperpour not_allowed)
				(footprints allowed)
			)
			(placement
				(enabled no)
				(sheetname "")
			)
			(fill
				(thermal_gap 0.5)
				(thermal_bridge_width 0.5)
				(island_removal_mode 0)
			)
			(polygon
				(pts
					(xy 119.6848 -24.8158) (xy 119.6848 -24.2062) (xy 119.8372 -24.2062) (xy 119.8372 -24.8158)
				)
			)
		)
		(zone
			(layer "B.Cu")
			(hatch none 0.5)
			(connect_pads
				(clearance 0)
			)
			(min_thickness 0.25)
			(keepout
				(tracks not_allowed)
				(vias allowed)
				(pads allowed)
				(copperpour not_allowed)
				(footprints allowed)
			)
			(placement
				(enabled no)
				(sheetname "")
			)
			(fill
				(thermal_gap 0.5)
				(thermal_bridge_width 0.5)
				(island_removal_mode 0)
			)
			(polygon
				(pts
					(xy 119.6848 -24.8158) (xy 119.6848 -24.2062) (xy 119.8372 -24.2062) (xy 119.8372 -24.8158)
				)
			)
		)
	)
)
